FILE_TYPE = CONNECTIVITY;
{Allegro Design Entry HDL 17.2-2016 S081 (4005846) 1/11/2022}
"PAGE_NUMBER" = 161;
0"NC";
1"GND\g";
2"AGND_HSC\g";
3"AGND_HSC\g";
4"GND\g";
5"GND\g";
6"AGND_HSC\g";
7"AGND_HSC\g";
8"GND\g";
9"P3V3_AUX\g";
10"HSC_VDD\g";
11"AGND_HSC\g";
12"P12V_AUX\g";
13"AGND_HSC\g";
14"GND\g";
15"AGND_HSC\g";
16"AGND_HSC\g";
17"PDB_PRSNT_N";
18"HSC_EN";
19"HSC_ADDR";
20"HSC_VDD18";
21"HSC_ON_R";
22"HSC_EN_R";
23"MB0_P12V_STBY_PWRGD";
24"HSC_VTEMP";
25"HSC_D_OC_R";
26"IRQ_SML1_PMBUS_ALERT";
27"HSC_VIN_UVW_N";
28"P12V_PSU_FUSE";
29"HSC_VDD_R";
30"SMB_SML1_PMBUS_HSC_SCL";
31"SMB_SML1_PMBUS_HSC_SDA";
32"HSC_VSENSE";
33"IRQ_SML1_PMBUS_ALERT_N";
34"P12V_PSU\g";
35"AGND_HSC\g";
36"P12V_PSU_FUSE";
37"GND\g"VOLTAGE"0";
38"HSC_ON";
39"HSC_EN";
40"SMB_SML1_PMBUS_HSC_L_SCL";
41"SMB_SML1_PMBUS_HSC_R_SDA";
42"HSC_VDD\g";
43"P12V_AUX\g";
44"GND\g";
45"AGND_HSC\g";
46"HSC_IMON";
47"AGND_HSC\g";
48"IRQ_HSC_FAULT_N";
49"HSC_D_OC";
50"HSC_MODE";
51"HSC_SS";
52"AGND_HSC\g";
53"HSC_VOSEN";
54"HSC_FAULT";
55"HSC_CS";
56"HSC_OCREF";
57"HSC_SCREF";
58"HSC_FLT_TYPE";
59"AGND_HSC\g";
60"HSC_VDD\g";
61"AGND_HSC\g";
62"GND\g";
%"Q_RES"
"1","(-13675,650)","0","pure_quanta","I10";
;
LOCATION"R4901"
$SEC"1"
CDS_SEC"1"
MATERIAL"CHIP"
VALUE"82K"
TOLERANCE"1%"
PACK_TYPE"0402LF"
WATTAGE"1/16W"
PART_NUMBER"CS38202FB01"
CDS_LIB"pure_quanta";
"B"
$PN"2"18;
"A"
$PN"1"28;
%"GND"
"1","(-13375,-200)","0","pure_quanta_power","I11";
;
ROOM"VR_DDR1_POWER_STAGE"
SIZE"1B"
CDS_LIB"pure_quanta_power"
HDL_POWER"GND";
"A<SIZE-1..0>\NAC"1;
%"Q_RES"
"2","(-13375,50)","0","pure_quanta","I12";
;
LOCATION"R2585"
$SEC"1"
CDS_SEC"1"
PACK_TYPE"0402LF"
PART_NUMBER"CS33162FB02"
MATERIAL"CHIP"
WATTAGE"1/16W"
VALUE"31.6K"
TOLERANCE"1%"
CDS_LIB"pure_quanta";
"A"
$PN"1"18;
"B"
$PN"2"1;
%"Q_CAP"
"1","(-12750,150)","0","pure_quanta","I13";
;
LOCATION"C1798"
$SEC"1"
CDS_SEC"1"
PACK_TYPE"C0402"
VALUE"100NF"
PART_NUMBER"CH4106K1B01"
MATERIAL"X7R"
VOLTAGE"50V"
TOLERANCE"10%"
CDS_LIB"pure_quanta";
"B"
$PN"2"2;
"A"
$PN"1"18;
%"UNIVERSAL_GND"
"1","(-12750,-200)","0","pure_quanta_power","I14";
;
HDL_POWER"AGND_HSC"
CDS_LIB"pure_quanta_power";
"A"2;
%"UNIVERSAL_GND"
"1","(-12850,1550)","0","pure_quanta_power","I17";
;
HDL_POWER"AGND_HSC"
CDS_LIB"pure_quanta_power";
"A"3;
%"GND"
"1","(-11775,775)","0","pure_quanta_power","I18";
;
ROOM"VR_DDR1_POWER_STAGE"
SIZE"1B"
CDS_LIB"pure_quanta_power"
HDL_POWER"GND";
"A<SIZE-1..0>\NAC"4;
%"Q_RES"
"1","(-11450,1025)","0","pure_quanta","I19";
;
LOCATION"PR3002"
$SEC"1"
CDS_SEC"1"
PART_NUMBER"CS00002JB13"
VALUE"0"
MATERIAL"CHIP"
WATTAGE"1/16W"
TOLERANCE"5%"
PACK_TYPE"0402LF"
CDS_LIB"pure_quanta";
"B"
$PN"2"6;
"A"
$PN"1"4;
%"UNIVERSAL_GND"
"1","(-15500,-525)","0","pure_quanta_power","I2";
;
CDS_LIB"pure_quanta_power"
HDL_POWER"GND";
"A"5;
%"UNIVERSAL_GND"
"1","(-11000,825)","0","pure_quanta_power","I20";
;
HDL_POWER"AGND_HSC"
CDS_LIB"pure_quanta_power";
"A"6;
%"UNIVERSAL_GND"
"1","(-9975,1250)","0","pure_quanta_power","I21";
;
HDL_POWER"AGND_HSC"
CDS_LIB"pure_quanta_power";
"A"7;
%"Q_RES"
"2","(-9975,1450)","0","pure_quanta","I22";
;
LOCATION"R1117"
$SEC"1"
CDS_SEC"1"
WATTAGE"1/16W"
VALUE"6.19K"
MATERIAL"CHIP"
TOLERANCE"1%"
PART_NUMBER"CS26192FB03"
PACK_TYPE"0402LF"
CDS_LIB"pure_quanta";
"A"
$PN"1"23;
"B"
$PN"2"7;
%"Q_RES"
"1","(-14625,2500)","0","pure_quanta","I24";
;
$LOCATION"R3924"
CDS_LOCATION"R3924"
$SEC"1"
CDS_SEC"1"
MATERIAL"CHIP"
VALUE"0"
TOLERANCE"5%"
PART_NUMBER"CS00002JB13"
PACK_TYPE"0402LF"
WATTAGE"1/16W"
CDS_LIB"pure_quanta";
"B"
$PN"2"26;
"A"
$PN"1"33;
%"Q_CAP"
"1","(-15425,3625)","0","pure_quanta","I27";
;
LOCATION"PC2186"
$SEC"1"
CDS_SEC"1"
VALUE"1UF"
VOLTAGE"25V"
MATERIAL"X6S"
PART_NUMBER"CH5104KEB02"
PACK_TYPE"C0402"
CDS_LIB"pure_quanta"
TOLERANCE"10%";
"B"
$PN"2"61;
"A"
$PN"1"29;
%"CONN3_210HP1030BR1"
"1","(-14850,2800)","2","pure_quanta","I28";
;
$LOCATION"JP10"
CDS_LOCATION"JP10"
$SEC"1"
CDS_SEC"1"
MATERIAL"IO"
PART_TYPE"THLF"
VALUE"CONN3_210-HP1-030BR1"
PART_NUMBER"DFHD03MS213"
NEEDS_NO_SIZE"TRUE"
CDS_LMAN_SYM_OUTLINE"-50,100,50,-100"
CDS_LIB"pure_quanta";
"1"
$PN"1"30;
"2"
$PN"2"31;
"3"
$PN"3"8;
%"UNIVERSAL_GND"
"1","(-14925,3350)","0","pure_quanta_power","I29";
;
HDL_POWER"AGND_HSC"
CDS_LIB"pure_quanta_power";
"A"61;
%"GND"
"1","(-14275,-525)","0","pure_quanta_power","I3";
;
ROOM"VR_DDR1_POWER_STAGE"
SIZE"1B"
CDS_LIB"pure_quanta_power"
HDL_POWER"GND";
"A<SIZE-1..0>\NAC"62;
%"Q_CAP"
"1","(-14925,3600)","0","pure_quanta","I30";
;
LOCATION"PC2187"
$SEC"1"
CDS_SEC"1"
PACK_TYPE"C0402"
VALUE"1UF"
VOLTAGE"25V"
MATERIAL"X6S"
PART_NUMBER"CH5104KEB02"
TOLERANCE"10%"
CDS_LIB"pure_quanta";
"B"
$PN"2"61;
"A"
$PN"1"29;
%"GND"
"1","(-14575,2650)","0","pure_quanta_power","I33";
;
ROOM"VR_DDR1_POWER_STAGE"
CDS_LIB"pure_quanta_power"
SIZE"1B"
HDL_POWER"GND";
"A<SIZE-1..0>\NAC"8;
%"Q_RES"
"1","(-14225,2675)","1","pure_quanta","I34";
;
$LOCATION"R3925"
CDS_LOCATION"R3925"
$SEC"1"
CDS_SEC"1"
WATTAGE"1/16W"
MATERIAL"CHIP"
PART_NUMBER"CS21002FB06"
PACK_TYPE"0402LF"
TOLERANCE"1%"
VALUE"1K"
CDS_LIB"pure_quanta";
"B"
$PN"2"9;
"A"
$PN"1"26;
%"UNIVERSAL_POWER"
"1","(-14225,2850)","0","pure_quanta_power","I35";
;
HDL_POWER"P3V3_AUX"
CDS_LIB"pure_quanta_power";
"A"9;
%"Q_RES"
"1","(-13675,3075)","0","pure_quanta","I36";
;
LOCATION"R1714"
$SEC"1"
CDS_SEC"1"
MATERIAL"CHIP"
TOLERANCE"5%"
WATTAGE"1/16W"
VALUE"0"
PACK_TYPE"0402LF"
PART_NUMBER"CS00002JB13"
CDS_LIB"pure_quanta";
"B"
$PN"2"41;
"A"
$PN"1"31;
%"Q_RES"
"1","(-13675,3175)","0","pure_quanta","I37";
;
LOCATION"R3909"
$SEC"1"
CDS_SEC"1"
MATERIAL"CHIP"
TOLERANCE"1%"
VALUE"33.2"
PACK_TYPE"0402LF"
WATTAGE"1/16W"
PART_NUMBER"CS03322FB03"
CDS_LIB"pure_quanta";
"B"
$PN"2"40;
"A"
$PN"1"30;
%"UNIVERSAL_GND"
"1","(-13700,3575)","0","pure_quanta_power","I38";
;
HDL_POWER"AGND_HSC"
CDS_LIB"pure_quanta_power";
"A"35;
%"Q_RES"
"1","(-15225,4050)","1","pure_quanta","I39";
;
LOCATION"PR2149"
$SEC"1"
CDS_SEC"1"
WATTAGE"1/16W"
MATERIAL"CHIP"
VALUE"0"
PART_NUMBER"CS00002JB13"
TOLERANCE"5%"
PACK_TYPE"0402LF"
CDS_LIB"pure_quanta";
"B"
$PN"2"10;
"A"
$PN"1"29;
%"Q_CAP"
"1","(-15500,-300)","0","pure_quanta","I4";
;
LOCATION"C1797"
$SEC"1"
CDS_SEC"1"
PART_NUMBER"CH4104K1B00"
VALUE"0.1UF"
PACK_TYPE"0402"
MATERIAL"X7R"
TOLERANCE"10%"
VOLTAGE"25V"
CDS_LIB"pure_quanta";
"B"
$PN"2"5;
"A"
$PN"1"17;
%"UNIVERSAL_POWER"
"1","(-15225,4275)","0","pure_quanta_power","I41";
;
HDL_POWER"HSC_VDD"
ROOM"AUX_SW"
CDS_LIB"pure_quanta_power"
BOM_COST"MIO_VRD_SB";
"A"10;
%"GND"
"1","(-14775,4050)","0","pure_quanta_power","I42";
;
ROOM"VR_DDR1_POWER_STAGE"
CDS_LIB"pure_quanta_power"
SIZE"1B"
HDL_POWER"GND";
"A<SIZE-1..0>\NAC"37;
%"ZENER_AC"
"1","(-14775,4275)","1","pure_quanta","I43";
;
LOCATION"PD13"
$SEC"1"
CDS_SEC"1"
MATERIAL"IC"
PART_NUMBER"BC0MDJ14000"
VALUE"5.0SMDJ14A"
PART_TYPE"SMLF"
CDS_LIB"pure_quanta"
CDS_LMAN_SYM_OUTLINE"-75,50,75,-50"
NEEDS_NO_SIZE"TRUE";
"C"
$PN"C"36;
"A"
$PN"A"37;
%"Q_FUSE"
"1","(-14775,4625)","3","pure_quanta","I44";
;
$LOCATION"FS1"
CDS_LOCATION"FS1"
$SEC"1"
CDS_SEC"1"
MATERIAL"IC"
PART_NUMBER"DKK00XFU000"
VALUE"20A/125V"
PACK_TYPE"SMLF"
CDS_LIB"pure_quanta"
NEEDS_NO_SIZE"TRUE";
"2 \B"
$PN"2"36;
"1 \B"
$PN"1"34;
%"UNIVERSAL_POWER"
"1","(-14775,4950)","0","pure_quanta_power","I45";
;
HDL_POWER"P12V_PSU"
ROOM"AUX_SW"
CDS_LIB"pure_quanta_power"
BOM_COST"MIO_VRD_SB";
"A"34;
%"Q_CAP"
"1","(-14225,4350)","0","pure_quanta","I46";
;
LOCATION"PC2188"
$SEC"1"
CDS_SEC"1"
VOLTAGE"25V"
VALUE"1UF"
MATERIAL"X6S"
PACK_TYPE"C0402"
PART_NUMBER"CH5104KEB02"
CDS_LIB"pure_quanta"
TOLERANCE"10%";
"B"
$PN"2"37;
"A"
$PN"1"34;
%"Q_RES"
"2","(-13700,3900)","0","pure_quanta","I47";
;
LOCATION"PR3927"
$SEC"1"
CDS_SEC"1"
WATTAGE"1/16W"
MATERIAL"CHIP"
PACK_TYPE"0402LF"
PART_NUMBER"CS24992BB04"
TOLERANCE"0.1%"
VALUE"4.99K"
CDS_LIB"pure_quanta";
"A"
$PN"1"32;
"B"
$PN"2"35;
%"Q_RES"
"2","(-13700,4350)","0","pure_quanta","I48";
;
LOCATION"PR3926"
$SEC"1"
CDS_SEC"1"
MATERIAL"CHIP"
TOLERANCE"0.1%"
WATTAGE"1/16W"
PACK_TYPE"0402LF"
VALUE"75K"
PART_NUMBER"CS37502BB01"
CDS_LIB"pure_quanta";
"A"
$PN"1"34;
"B"
$PN"2"32;
%"UNIVERSAL_GND"
"1","(-13325,1875)","0","pure_quanta_power","I49";
;
HDL_POWER"AGND_HSC"
CDS_LIB"pure_quanta_power";
"A"11;
%"Q_RES"
"2","(-14800,-250)","0","pure_quanta","I5";
;
LOCATION"R3907"
$SEC"1"
CDS_SEC"1"
TOLERANCE"1%"
VALUE"33K"
PART_NUMBER"CS33302FB00"
PACK_TYPE"0402LF"
WATTAGE"1/16W"
MATERIAL"CHIP"
CDS_LIB"pure_quanta";
"A"
$PN"1"17;
"B"
$PN"2"62;
%"Q_CAP"
"1","(-13325,2175)","0","pure_quanta","I50";
;
$LOCATION"PC2103"
CDS_LOCATION"PC2103"
$SEC"1"
CDS_SEC"1"
PACK_TYPE"C0402"
MATERIAL"X6S"
VALUE"1UF"
VOLTAGE"25V"
PART_NUMBER"CH5104KEB02"
CDS_LIB"pure_quanta"
TOLERANCE"10%";
"B"
$PN"2"11;
"A"
$PN"1"20;
%"Q_RES"
"1","(-13100,2525)","0","pure_quanta","I51";
;
LOCATION"PR3928"
$SEC"1"
CDS_SEC"1"
PACK_TYPE"0402LF"
TOLERANCE"5%"
VALUE"0"
PART_NUMBER"CS00002JB13"
WATTAGE"1/16W"
MATERIAL"CHIP"
CDS_LIB"pure_quanta";
"B"
$PN"2"21;
"A"
$PN"1"38;
%"Q_RES"
"1","(-12850,1750)","1","pure_quanta","I52";
;
LOCATION"PR3930"
$SEC"1"
CDS_SEC"1"
VALUE"0"
TOLERANCE"5%"
PACK_TYPE"0402LF"
WATTAGE"1/16W"
PART_NUMBER"CS00002JB13"
MATERIAL"CHIP"
CDS_LIB"pure_quanta";
"B"
$PN"2"19;
"A"
$PN"1"3;
%"Q_RES"
"1","(-12850,2150)","1","pure_quanta","I53";
;
LOCATION"PR3929"
$SEC"1"
CDS_SEC"1"
MATERIAL"EMPTY"
PART_NUMBER"CS21002FB06"
VALUE"1K"
TOLERANCE"1%"
PACK_TYPE"0402LF"
WATTAGE"1/16W"
CDS_LIB"pure_quanta";
"B"
$PN"2"20;
"A"
$PN"1"19;
%"Q_RES"
"1","(-13100,2650)","0","pure_quanta","I54";
;
LOCATION"R2586"
$SEC"1"
CDS_SEC"1"
WATTAGE"1/16W"
VALUE"0"
MATERIAL"CHIP"
PART_NUMBER"CS00002JB13"
TOLERANCE"5%"
PACK_TYPE"0402LF"
CDS_LIB"pure_quanta";
"B"
$PN"2"22;
"A"
$PN"1"39;
%"UNIVERSAL_POWER"
"1","(-13600,2850)","0","pure_quanta_power","I55";
;
HDL_POWER"HSC_VDD"
ROOM"AUX_SW"
BOM_COST"MIO_VRD_SB"
CDS_LIB"pure_quanta_power";
"A"60;
%"Q_RES"
"1","(-13100,2775)","0","pure_quanta","I56";
;
$LOCATION"PR2106"
CDS_LOCATION"PR2106"
$SEC"1"
CDS_SEC"1"
WATTAGE"1/16W"
PACK_TYPE"0402LF"
VALUE"10K"
PART_NUMBER"CS31002FB08"
TOLERANCE"1%"
MATERIAL"CHIP"
CDS_LIB"pure_quanta";
"B"
$PN"2"27;
"A"
$PN"1"60;
%"UNIVERSAL_GND"
"1","(-12075,1925)","0","pure_quanta_power","I57";
;
HDL_POWER"AGND_HSC"
CDS_LIB"pure_quanta_power";
"A"59;
%"MP5990GMA1111Z"
"1","(-11400,3050)","0","pure_quanta","I58";
;
LOCATION"PU289"
$SEC"1"
CDS_SEC"1"
MATERIAL"IC"
PART_NUMBER"AL005990A03"
VALUE"MP5990GMA-1111-Z"
PART_TYPE"SMLF"
CDS_LMAN_SYM_OUTLINE"-425,1125,425,-1125"
NEEDS_NO_SIZE"TRUE"
CDS_LIB"pure_quanta";
"ADDR"
$PN"23"19;
"VDD18"
$PN"19"20;
"VDD33_2"
$PN"45"29;
"VDD33_1"
$PN"17"29;
"VINSEN"
$PN"9"32;
"VIN10"
$PN"43"34;
"FLT_TYPE"
$PN"40"58;
"GND2"
$PN"44"59;
"VIN1"
$PN"1"34;
"VOUT4"
$PN"30"43;
"VOSEN"
$PN"24"53;
"VOUT10"
$PN"36"43;
"VIN9"
$PN"42"34;
"CS"
$PN"20"55;
"IMON"
$PN"21"46;
"VOUT6"
$PN"32"43;
"SS"
$PN"16"51;
"SCREF_OCWREF"
$PN"25"57;
"OCREF"
$PN"22"56;
"VTEMP"
$PN"15"24;
"VIN6"
$PN"6"34;
"VIN5"
$PN"5"34;
"ON"
$PN"38"21;
"VOUT8"
$PN"34"43;
"PG||OCW#"
$PN"13"23;
"VIN8"
$PN"8"34;
"MODE"
$PN"41"50;
"VOUT7"
$PN"33"43;
"VIN7"
$PN"7"34;
"GOK"
$PN"39"54;
"ALT# \B"
$PN"10"26;
"VOUT9"
$PN"35"43;
"VOUT5"
$PN"31"43;
"D_OC"
$PN"37"25;
"SCL"
$PN"11"40;
"VIN_UVW# \B"
$PN"14"27;
"SDA"
$PN"12"41;
"GND1"
$PN"18"59;
"VIN4"
$PN"4"34;
"VIN3"
$PN"3"34;
"EN"
$PN"26"22;
"VIN2"
$PN"2"34;
"VOUT1"
$PN"27"43;
"VOUT2"
$PN"28"43;
"VOUT3"
$PN"29"43;
%"Q_CAP"
"1","(-13175,3900)","0","pure_quanta","I59";
;
LOCATION"PC2189"
$SEC"1"
CDS_SEC"1"
PART_NUMBER"CH31006KB18"
MATERIAL"X7R"
VALUE"0.01UF"
PACK_TYPE"C0402"
VOLTAGE"50V"
CDS_LIB"pure_quanta"
TOLERANCE"10%";
"B"
$PN"2"35;
"A"
$PN"1"32;
%"Q_RES"
"2","(-14850,250)","0","pure_quanta","I6";
;
LOCATION"R3923"
$SEC"1"
CDS_SEC"1"
WATTAGE"1/16W"
TOLERANCE"1%"
VALUE"63.4K"
PART_NUMBER"CS36342FB04"
PACK_TYPE"0402LF"
CDS_LIB"pure_quanta"
MATERIAL"CHIP";
"A"
$PN"1"28;
"B"
$PN"2"17;
%"Q_RES"
"2","(-9975,1900)","0","pure_quanta","I63";
;
LOCATION"R3933"
$SEC"1"
CDS_SEC"1"
PART_NUMBER"CS31692FB03"
TOLERANCE"1%"
PACK_TYPE"0402LF"
MATERIAL"CHIP"
VALUE"16.9K"
WATTAGE"1/16W"
CDS_LIB"pure_quanta";
"A"
$PN"1"12;
"B"
$PN"2"23;
%"UNIVERSAL_POWER"
"1","(-9975,2100)","0","pure_quanta_power","I64";
;
HDL_POWER"P12V_AUX"
ROOM"AUX_SW"
BOM_COST"MIO_VRD_SB"
CDS_LIB"pure_quanta_power";
"A"12;
%"Q_RES"
"1","(-10150,2975)","0","pure_quanta","I65";
;
$LOCATION"PR1131"
CDS_LOCATION"PR1131"
$SEC"1"
CDS_SEC"1"
PART_NUMBER"CS22002BB07"
WATTAGE"1/16W"
MATERIAL"CHIP"
PACK_TYPE"0402LF"
VALUE"2K"
TOLERANCE"0.1%"
CDS_LIB"pure_quanta";
"B"
$PN"2"13;
"A"
$PN"1"55;
%"UNIVERSAL_GND"
"1","(-9625,2875)","0","pure_quanta_power","I66";
;
HDL_POWER"AGND_HSC"
CDS_LIB"pure_quanta_power";
"A"13;
%"UNIVERSAL_GND"
"1","(-9775,3675)","0","pure_quanta_power","I69";
;
HDL_POWER"AGND_HSC"
CDS_LIB"pure_quanta_power";
"A"52;
%"GND"
"1","(-15075,900)","0","pure_quanta_power","I7";
;
ROOM"VR_DDR1_POWER_STAGE"
SIZE"1B"
CDS_LIB"pure_quanta_power"
HDL_POWER"GND";
"A<SIZE-1..0>\NAC"14;
%"Q_RES"
"2","(-10250,3975)","0","pure_quanta","I70";
;
LOCATION"PR3932"
$SEC"1"
CDS_SEC"1"
PACK_TYPE"0402LF"
PART_NUMBER"CS24992BB04"
MATERIAL"CHIP"
TOLERANCE"0.1%"
WATTAGE"1/16W"
VALUE"4.99K"
CDS_LIB"pure_quanta";
"A"
$PN"1"53;
"B"
$PN"2"52;
%"Q_RES"
"2","(-10325,4425)","0","pure_quanta","I71";
;
LOCATION"PR3931"
$SEC"1"
CDS_SEC"1"
PART_NUMBER"CS37502BB01"
PACK_TYPE"0402LF"
TOLERANCE"0.1%"
MATERIAL"CHIP"
WATTAGE"1/16W"
VALUE"75K"
CDS_LIB"pure_quanta";
"A"
$PN"1"43;
"B"
$PN"2"53;
%"Q_CAP"
"1","(-9775,3975)","0","pure_quanta","I72";
;
LOCATION"PC2190"
$SEC"1"
CDS_SEC"1"
PACK_TYPE"C0402"
PART_NUMBER"CH31006KB18"
VALUE"0.01UF"
MATERIAL"X7R"
VOLTAGE"50V"
CDS_LIB"pure_quanta"
TOLERANCE"10%";
"B"
$PN"2"52;
"A"
$PN"1"53;
%"UNIVERSAL_GND"
"1","(-9500,2000)","0","pure_quanta_power","I74";
;
HDL_POWER"AGND_HSC"
CDS_LIB"pure_quanta_power";
"A"15;
%"Q_CAP"
"1","(-9500,2175)","0","pure_quanta","I75";
;
LOCATION"PC2191"
$SEC"1"
CDS_SEC"1"
PART_NUMBER"CH3683K1B09"
VALUE"0.068UF"
VOLTAGE"16V"
PACK_TYPE"0402"
MATERIAL"X7R"
TOLERANCE"10%"
CDS_LIB"pure_quanta";
"B"
$PN"2"15;
"A"
$PN"1"51;
%"UNIVERSAL_GND"
"1","(-8625,2100)","0","pure_quanta_power","I77";
;
HDL_POWER"AGND_HSC"
CDS_LIB"pure_quanta_power";
"A"47;
%"Q_CAP"
"1","(-8925,2425)","0","pure_quanta","I78";
;
LOCATION"PC2192"
$SEC"1"
CDS_SEC"1"
PACK_TYPE"C0402"
MATERIAL"X7R"
VALUE"0.001UF"
VOLTAGE"50V"
PART_NUMBER"CH30106KB19"
TOLERANCE"10%"
CDS_LIB"pure_quanta";
"B"
$PN"2"47;
"A"
$PN"1"24;
%"Q_RES"
"1","(-8950,3575)","0","pure_quanta","I79";
;
LOCATION"R2588"
$SEC"1"
CDS_SEC"1"
PACK_TYPE"0402LF"
PART_NUMBER"CS02202FB02"
TOLERANCE"1%"
MATERIAL"CHIP"
WATTAGE"1/16W"
VALUE"22"
CDS_LIB"pure_quanta";
"B"
$PN"2"48;
"A"
$PN"1"54;
%"CONN3_210HP1030BR1"
"1","(-14825,1100)","0","pure_quanta","I8";
;
LOCATION"JP4003"
$SEC"1"
CDS_SEC"1"
VALUE"CONN3_210-HP1-030BR1"
PART_TYPE"THLF"
PART_NUMBER"DFHD03MS213"
MATERIAL"IO"
NEEDS_NO_SIZE"TRUE"
CDS_LMAN_SYM_OUTLINE"-50,100,50,-100"
CDS_LIB"pure_quanta";
"1"
$PN"1"0;
"2"
$PN"2"17;
"3"
$PN"3"14;
%"Q_RES"
"1","(-8950,3400)","0","pure_quanta","I80";
;
LOCATION"R3934"
$SEC"1"
CDS_SEC"1"
PART_NUMBER"CS02202FB02"
VALUE"22"
TOLERANCE"1%"
MATERIAL"CHIP"
PACK_TYPE"0402LF"
WATTAGE"1/16W"
CDS_LIB"pure_quanta";
"B"
$PN"2"49;
"A"
$PN"1"25;
%"Q_RES"
"2","(-8450,2450)","0","pure_quanta","I81";
;
LOCATION"PR3935"
$SEC"1"
CDS_SEC"1"
VALUE"10K"
TOLERANCE"1%"
PART_NUMBER"CS31002FB08"
WATTAGE"1/16W"
PACK_TYPE"0402LF"
MATERIAL"CHIP"
CDS_LIB"pure_quanta";
"A"
$PN"1"24;
"B"
$PN"2"47;
%"UNIVERSAL_GND"
"1","(-7625,2600)","0","pure_quanta_power","I83";
;
HDL_POWER"AGND_HSC"
CDS_LIB"pure_quanta_power";
"A"45;
%"Q_CAP"
"1","(-8100,2850)","0","pure_quanta","I84";
;
LOCATION"PC2193"
$SEC"1"
CDS_SEC"1"
PACK_TYPE"C0402"
VALUE"0.047UF"
MATERIAL"X7R"
VOLTAGE"25V"
PART_NUMBER"CH3474K1B04"
CDS_LIB"pure_quanta"
TOLERANCE"10%";
"B"
$PN"2"45;
"A"
$PN"1"46;
%"Q_RES"
"1","(-8125,3275)","0","pure_quanta","I85";
;
LOCATION"PR3937"
$SEC"1"
CDS_SEC"1"
PACK_TYPE"0402LF"
MATERIAL"CHIP"
VALUE"120K"
WATTAGE"1/16W"
PART_NUMBER"CS41202FB05"
TOLERANCE"1%"
CDS_LIB"pure_quanta";
"B"
$PN"2"16;
"A"
$PN"1"50;
%"Q_RES"
"2","(-7625,2875)","0","pure_quanta","I86";
;
$LOCATION"PR1133"
CDS_LOCATION"PR1133"
$SEC"1"
CDS_SEC"1"
PACK_TYPE"0402LF"
PART_NUMBER"CS22002BB07"
VALUE"2K"
TOLERANCE"0.1%"
MATERIAL"CHIP"
WATTAGE"1/16W"
CDS_LIB"pure_quanta";
"A"
$PN"1"46;
"B"
$PN"2"45;
%"UNIVERSAL_GND"
"1","(-7550,3200)","0","pure_quanta_power","I87";
;
HDL_POWER"AGND_HSC"
CDS_LIB"pure_quanta_power";
"A"16;
%"GND"
"1","(-9175,3725)","0","pure_quanta_power","I88";
;
ROOM"VR_DDR1_POWER_STAGE"
CDS_LIB"pure_quanta_power"
SIZE"1B"
HDL_POWER"GND";
"A<SIZE-1..0>\NAC"44;
%"SS15P3SM386A"
"1","(-9175,4225)","1","pure_quanta","I89";
;
LOCATION"PD111"
$SEC"1"
CDS_SEC"1"
VALUE"SS15P3S-M3/86A"
PART_NUMBER"BC015P3SZ00"
MATERIAL"IC"
PART_TYPE"SMLF"
CDS_LMAN_SYM_OUTLINE"-125,100,125,-100"
NEEDS_NO_SIZE"TRUE"
CDS_LIB"pure_quanta";
"ANODE_2"
$PN"2"44;
"CATHODE"
$PN"K"43;
"ANODE_1"
$PN"1"44;
%"MOSFET_NCH_GDS_ESD_PROTECTED"
"1","(-14300,-75)","0","pure_quanta","I9";
;
$LOCATION"U290"
CDS_LOCATION"U290"
$SEC"1"
CDS_SEC"1"
VALUE"2N7002K"
PART_NUMBER"BAM70020002"
MATERIAL"IC"
PART_TYPE"SMLF"
NEEDS_NO_SIZE"TRUE"
CDS_LIB"pure_quanta"
CDS_LMAN_SYM_OUTLINE"-125,150,125,-150";
"S"
$PN"S"62;
"G"
$PN"G"17;
"D"
$PN"D"18;
%"UNIVERSAL_POWER"
"1","(-8575,4800)","0","pure_quanta_power","I90";
;
HDL_POWER"P12V_AUX"
ROOM"AUX_SW"
CDS_LIB"pure_quanta_power"
BOM_COST"MIO_VRD_SB";
"A"43;
%"Q_RES"
"2","(-8425,3900)","0","pure_quanta","I91";
;
LOCATION"R3936"
$SEC"1"
CDS_SEC"1"
PART_NUMBER"CS24702FB06"
MATERIAL"CHIP"
WATTAGE"1/16W"
TOLERANCE"1%"
PACK_TYPE"0402LF"
VALUE"4.7K"
CDS_LIB"pure_quanta";
"A"
$PN"1"42;
"B"
$PN"2"49;
%"UNIVERSAL_POWER"
"1","(-8225,4250)","0","pure_quanta_power","I92";
;
HDL_POWER"HSC_VDD"
ROOM"AUX_SW"
BOM_COST"MIO_VRD_SB"
CDS_LIB"pure_quanta_power";
"A"42;
%"Q_RES"
"2","(-8000,3900)","0","pure_quanta","I93";
;
LOCATION"R2587"
$SEC"1"
CDS_SEC"1"
PACK_TYPE"0402LF"
WATTAGE"1/16W"
MATERIAL"CHIP"
PART_NUMBER"CS24702FB06"
TOLERANCE"1%"
VALUE"4.7K"
CDS_LIB"pure_quanta";
"A"
$PN"1"42;
"B"
$PN"2"48;
END.
